# T6G (Grand Teton) — schematic netlist excerpt (pin names and nets, part order shuffled) for the footprints in the layout excerpt that follows; sources: Cadence DE-HDL packaged netlist, KiCad conversion of 04192023_DAF0TMB3IC0_F0TG_MB_C_brd_V02_OCP.brd

R6145  Q_RES  1K 1% CHIP  pkg 0402LF  page 84 : A = FM_BOARD_BMC_SKU_ID0 ; B = GND
C102  Q_CAP  100UF 4V 20% X6S  pkg C0805  page 334 : A = P1V8_CPU1_RT_1D ; B = GND
C178  Q_CAP  10UF 25V 10% X6S  pkg C0805  page 100 : A = P12V_MEM_CPU1 ; B = GND

(kicad_pcb
	(version 20260206)
	(generator "pcbnew")
	(generator_version "10.0")
	(general
		(thickness 1.6)
		(legacy_teardrops no)
	)
	(paper "A4")
	(title_block
		(title "04192023_DAF0TMB3IC0_F0TG_MB_C_brd_V02_OCP.brd")
		(comment 1 "Grand Teton / footprints 5662-5664 of 8354")
	)
	(layers
		(0 "F.Cu" signal "TOP")
		(4 "In1.Cu" signal "GND")
		(6 "In2.Cu" signal "IN1")
		(8 "In3.Cu" signal "GND1")
		(10 "In4.Cu" signal "IN2")
		(12 "In5.Cu" signal "GND2")
		(14 "In6.Cu" signal "IN3")
		(16 "In7.Cu" signal "GND3")
		(18 "In8.Cu" signal "VCC")
		(20 "In9.Cu" signal "VCC1")
		(22 "In10.Cu" signal "GND4")
		(24 "In11.Cu" signal "IN4")
		(26 "In12.Cu" signal "GND5")
		(28 "In13.Cu" signal "IN5")
		(30 "In14.Cu" signal "GND6")
		(32 "In15.Cu" signal "IN6")
		(34 "In16.Cu" signal "GND7")
		(2 "B.Cu" signal "BOTTOM")
		(9 "F.Adhes" user "F.Adhesive")
		(11 "B.Adhes" user "B.Adhesive")
		(13 "F.Paste" user "Package Geometry/Pastemask Top")
		(15 "B.Paste" user "Package Geometry/Pastemask Bottom")
		(5 "F.SilkS" user "Ref Des/Silkscreen Top")
		(7 "B.SilkS" user "Ref Des/Silkscreen Bottom")
		(1 "F.Mask" user "Board Geometry/Soldermask Top")
		(3 "B.Mask" user "Board Geometry/Soldermask Bottom")
		(17 "Dwgs.User" user "User.Drawings")
		(19 "Cmts.User" user "User.Comments")
		(21 "Eco1.User" user "User.Eco1")
		(23 "Eco2.User" user "User.Eco2")
		(25 "Edge.Cuts" user "Board Geometry/Outline")
		(27 "Margin" user)
		(31 "F.CrtYd" user "Package Geometry/Place Bound Top")
		(29 "B.CrtYd" user "Package Geometry/Place Bound Bottom")
		(35 "F.Fab" user "Ref Des/Assembly Top")
		(33 "B.Fab" user "Ref Des/Assembly Bottom")
	)
	(footprint ""
		(layer "B.Cu")
		(at 164.363908 -113.013744)
		(property "Reference" "R6145"
			(at 0 0 0)
			(layer "B.SilkS")
			(hide yes)
			(effects
				(font
					(size 1.27 1.27)
				)
				(justify mirror)
			)
		)
		(property "Value" ""
			(at 0 0 0)
			(layer "B.Fab")
			(effects
				(font
					(size 1.27 1.27)
				)
				(justify mirror)
			)
		)
		(duplicate_pad_numbers_are_jumpers no)
		(fp_line
			(start -0.7874 -0.4064)
			(end -0.7874 0.4064)
			(stroke
				(width 0.1524)
				(type default)
			)
			(layer "B.SilkS")
		)
		(fp_line
			(start -0.7874 0.4064)
			(end 0.7874 0.4064)
			(stroke
				(width 0.1524)
				(type default)
			)
			(layer "B.SilkS")
		)
		(fp_line
			(start 0.7874 -0.4064)
			(end -0.7874 -0.4064)
			(stroke
				(width 0.1524)
				(type default)
			)
			(layer "B.SilkS")
		)
		(fp_line
			(start 0.7874 0.4064)
			(end 0.7874 -0.4064)
			(stroke
				(width 0.1524)
				(type default)
			)
			(layer "B.SilkS")
		)
		(fp_line
			(start -0.67945 -0.3048)
			(end -0.67945 0.3048)
			(stroke
				(width 0.1)
				(type default)
			)
			(layer "B.Fab")
		)
		(fp_line
			(start -0.67945 0.3048)
			(end -0.120396 0.3048)
			(stroke
				(width 0.1)
				(type default)
			)
			(layer "B.Fab")
		)
		(fp_line
			(start -0.12065 -0.3048)
			(end -0.67945 -0.3048)
			(stroke
				(width 0.1)
				(type default)
			)
			(layer "B.Fab")
		)
		(fp_line
			(start -0.12065 -0.2794)
			(end -0.12065 -0.3048)
			(stroke
				(width 0.1)
				(type default)
			)
			(layer "B.Fab")
		)
		(fp_line
			(start -0.120396 0.2794)
			(end 0.12065 0.2794)
			(stroke
				(width 0.1)
				(type default)
			)
			(layer "B.Fab")
		)
		(fp_line
			(start -0.120396 0.3048)
			(end -0.120396 0.2794)
			(stroke
				(width 0.1)
				(type default)
			)
			(layer "B.Fab")
		)
		(fp_line
			(start 0.12065 -0.305054)
			(end 0.12065 -0.2794)
			(stroke
				(width 0.1)
				(type default)
			)
			(layer "B.Fab")
		)
		(fp_line
			(start 0.12065 -0.2794)
			(end -0.12065 -0.2794)
			(stroke
				(width 0.1)
				(type default)
			)
			(layer "B.Fab")
		)
		(fp_line
			(start 0.12065 0.2794)
			(end 0.12065 0.3048)
			(stroke
				(width 0.1)
				(type default)
			)
			(layer "B.Fab")
		)
		(fp_line
			(start 0.12065 0.3048)
			(end 0.67945 0.3048)
			(stroke
				(width 0.1)
				(type default)
			)
			(layer "B.Fab")
		)
		(fp_line
			(start 0.67945 -0.305054)
			(end 0.12065 -0.305054)
			(stroke
				(width 0.1)
				(type default)
			)
			(layer "B.Fab")
		)
		(fp_line
			(start 0.67945 0.3048)
			(end 0.67945 -0.305054)
			(stroke
				(width 0.1)
				(type default)
			)
			(layer "B.Fab")
		)
		(pad "1" smd circle
			(at 0.40005 0 180)
			(size 0 0)
			(layers "B.Cu" "B.Mask" "B.Paste")
			(net "FM_BOARD_BMC_SKU_ID0")
		)
		(pad "2" smd circle
			(at -0.40005 0 180)
			(size 0 0)
			(layers "B.Cu" "B.Mask" "B.Paste")
			(net "GND")
		)
	)
	(footprint ""
		(layer "B.Cu")
		(at 40.240204 -192.66027 180)
		(property "Reference" "C178"
			(at 0 0 0)
			(layer "B.SilkS")
			(hide yes)
			(effects
				(font
					(size 1.27 1.27)
				)
				(justify mirror)
			)
		)
		(property "Value" ""
			(at 0 0 0)
			(layer "B.Fab")
			(effects
				(font
					(size 1.27 1.27)
				)
				(justify mirror)
			)
		)
		(duplicate_pad_numbers_are_jumpers no)
		(fp_line
			(start 1.524 0.762)
			(end 1.524 -0.762)
			(stroke
				(width 0.1524)
				(type default)
			)
			(layer "B.SilkS")
		)
		(fp_line
			(start 1.524 -0.762)
			(end -1.524 -0.762)
			(stroke
				(width 0.1524)
				(type default)
			)
			(layer "B.SilkS")
		)
		(fp_line
			(start -1.524 0.762)
			(end 1.524 0.762)
			(stroke
				(width 0.1524)
				(type default)
			)
			(layer "B.SilkS")
		)
		(fp_line
			(start -1.524 -0.762)
			(end -1.524 0.762)
			(stroke
				(width 0.1524)
				(type default)
			)
			(layer "B.SilkS")
		)
		(fp_line
			(start 1.1049 0.724916)
			(end -1.1049 0.724916)
			(stroke
				(width 0.1)
				(type default)
			)
			(layer "B.Fab")
		)
		(fp_line
			(start 1.1049 -0.724916)
			(end 1.1049 0.724916)
			(stroke
				(width 0.1)
				(type default)
			)
			(layer "B.Fab")
		)
		(fp_line
			(start -1.1049 0.724916)
			(end -1.1049 -0.724916)
			(stroke
				(width 0.1)
				(type default)
			)
			(layer "B.Fab")
		)
		(fp_line
			(start -1.1049 -0.724916)
			(end 1.1049 -0.724916)
			(stroke
				(width 0.1)
				(type default)
			)
			(layer "B.Fab")
		)
		(pad "1" smd rect
			(at 0.889 0 180)
			(size 1.016 1.27)
			(layers "B.Cu" "B.Mask" "B.Paste")
			(net "P12V_MEM_CPU1")
		)
		(pad "2" smd rect
			(at -0.889 0 180)
			(size 1.016 1.27)
			(layers "B.Cu" "B.Mask" "B.Paste")
			(net "GND")
		)
	)
	(footprint ""
		(layer "B.Cu")
		(at 103.173276 -387.084062 -90)
		(property "Reference" "C102"
			(at 0 0 90)
			(layer "B.SilkS")
			(hide yes)
			(effects
				(font
					(size 1.27 1.27)
				)
				(justify mirror)
			)
		)
		(property "Value" ""
			(at 0 0 90)
			(layer "B.Fab")
			(effects
				(font
					(size 1.27 1.27)
				)
				(justify mirror)
			)
		)
		(duplicate_pad_numbers_are_jumpers no)
		(fp_line
			(start -1.524 0.762)
			(end 1.524 0.762)
			(stroke
				(width 0.1524)
				(type default)
			)
			(layer "B.SilkS")
		)
		(fp_line
			(start 1.524 0.762)
			(end 1.524 -0.762)
			(stroke
				(width 0.1524)
				(type default)
			)
			(layer "B.SilkS")
		)
		(fp_line
			(start -1.524 -0.762)
			(end -1.524 0.762)
			(stroke
				(width 0.1524)
				(type default)
			)
			(layer "B.SilkS")
		)
		(fp_line
			(start 1.524 -0.762)
			(end -1.524 -0.762)
			(stroke
				(width 0.1524)
				(type default)
			)
			(layer "B.SilkS")
		)
		(fp_line
			(start -1.1049 0.724916)
			(end -1.1049 -0.724916)
			(stroke
				(width 0.1)
				(type default)
			)
			(layer "B.Fab")
		)
		(fp_line
			(start 1.1049 0.724916)
			(end -1.1049 0.724916)
			(stroke
				(width 0.1)
				(type default)
			)
			(layer "B.Fab")
		)
		(fp_line
			(start -1.1049 -0.724916)
			(end 1.1049 -0.724916)
			(stroke
				(width 0.1)
				(type default)
			)
			(layer "B.Fab")
		)
		(fp_line
			(start 1.1049 -0.724916)
			(end 1.1049 0.724916)
			(stroke
				(width 0.1)
				(type default)
			)
			(layer "B.Fab")
		)
		(pad "1" smd rect
			(at 0.889 0 270)
			(size 1.016 1.27)
			(layers "B.Cu" "B.Mask" "B.Paste")
			(net "P1V8_CPU1_RT_1D")
		)
		(pad "2" smd rect
			(at -0.889 0 270)
			(size 1.016 1.27)
			(layers "B.Cu" "B.Mask" "B.Paste")
			(net "GND")
		)
	)
)
